(kicad_pcb
	(version 20260206)
	(generator "pcbnew")
	(generator_version "10.0")
	(general
		(thickness 1.6)
		(legacy_teardrops no)
	)
	(paper "A4")
	(title_block
		(title "01162023_DA0F0TEBIF0_F0T_Expander_BD_F_brd_V02_OCP.brd")
		(comment 1 "Grand Teton / footprints 2956-2961 of 9728")
	)
	(layers
		(0 "F.Cu" signal "TOP")
		(4 "In1.Cu" signal "GND")
		(6 "In2.Cu" signal "VCC")
		(8 "In3.Cu" signal "VCC1")
		(10 "In4.Cu" signal "GND1")
		(12 "In5.Cu" signal "IN1")
		(14 "In6.Cu" signal "GND2")
		(16 "In7.Cu" signal "IN2")
		(18 "In8.Cu" signal "GND3")
		(20 "In9.Cu" signal "IN3")
		(22 "In10.Cu" signal "GND4")
		(24 "In11.Cu" signal "IN4")
		(26 "In12.Cu" signal "GND5")
		(28 "In13.Cu" signal "IN5")
		(30 "In14.Cu" signal "GND6")
		(32 "In15.Cu" signal "IN6")
		(34 "In16.Cu" signal "GND7")
		(2 "B.Cu" signal "BOTTOM")
		(9 "F.Adhes" user "F.Adhesive")
		(11 "B.Adhes" user "B.Adhesive")
		(13 "F.Paste" user "Package Geometry/Pastemask Top")
		(15 "B.Paste" user "Package Geometry/Pastemask Bottom")
		(5 "F.SilkS" user "Ref Des/Silkscreen Top")
		(7 "B.SilkS" user "Ref Des/Silkscreen Bottom")
		(1 "F.Mask" user "Board Geometry/Soldermask Top")
		(3 "B.Mask" user "Board Geometry/Soldermask Bottom")
		(17 "Dwgs.User" user "User.Drawings")
		(19 "Cmts.User" user "User.Comments")
		(21 "Eco1.User" user "User.Eco1")
		(23 "Eco2.User" user "User.Eco2")
		(25 "Edge.Cuts" user "Board Geometry/Outline")
		(27 "Margin" user)
		(31 "F.CrtYd" user "Package Geometry/Place Bound Top")
		(29 "B.CrtYd" user "Package Geometry/Place Bound Bottom")
		(35 "F.Fab" user "Ref Des/Assembly Top")
		(33 "B.Fab" user "Ref Des/Assembly Bottom")
	)
	(footprint ""
		(layer "F.Cu")
		(at 206.118206 -306.074572 90)
		(property "Reference" "R1304"
			(at 0 0 90)
			(layer "F.SilkS")
			(hide yes)
			(effects
				(font
					(size 1.27 1.27)
				)
			)
		)
		(property "Value" ""
			(at 0 0 90)
			(layer "F.Fab")
			(effects
				(font
					(size 1.27 1.27)
				)
			)
		)
		(duplicate_pad_numbers_are_jumpers no)
		(fp_line
			(start 0.7874 -0.4064)
			(end 0.7874 0.4064)
			(stroke
				(width 0.1524)
				(type default)
			)
			(layer "F.SilkS")
		)
		(fp_line
			(start -0.7874 -0.4064)
			(end 0.7874 -0.4064)
			(stroke
				(width 0.1524)
				(type default)
			)
			(layer "F.SilkS")
		)
		(fp_line
			(start 0.7874 0.4064)
			(end -0.7874 0.4064)
			(stroke
				(width 0.1524)
				(type default)
			)
			(layer "F.SilkS")
		)
		(fp_line
			(start -0.7874 0.4064)
			(end -0.7874 -0.4064)
			(stroke
				(width 0.1524)
				(type default)
			)
			(layer "F.SilkS")
		)
		(fp_line
			(start -0.12065 -0.305054)
			(end -0.12065 -0.2794)
			(stroke
				(width 0.1)
				(type default)
			)
			(layer "F.Fab")
		)
		(fp_line
			(start -0.67945 -0.305054)
			(end -0.12065 -0.305054)
			(stroke
				(width 0.1)
				(type default)
			)
			(layer "F.Fab")
		)
		(fp_line
			(start 0.67945 -0.3048)
			(end 0.67945 0.3048)
			(stroke
				(width 0.1)
				(type default)
			)
			(layer "F.Fab")
		)
		(fp_line
			(start 0.12065 -0.3048)
			(end 0.67945 -0.3048)
			(stroke
				(width 0.1)
				(type default)
			)
			(layer "F.Fab")
		)
		(fp_line
			(start 0.12065 -0.2794)
			(end 0.12065 -0.3048)
			(stroke
				(width 0.1)
				(type default)
			)
			(layer "F.Fab")
		)
		(fp_line
			(start -0.12065 -0.2794)
			(end 0.12065 -0.2794)
			(stroke
				(width 0.1)
				(type default)
			)
			(layer "F.Fab")
		)
		(fp_line
			(start 0.120396 0.2794)
			(end -0.12065 0.2794)
			(stroke
				(width 0.1)
				(type default)
			)
			(layer "F.Fab")
		)
		(fp_line
			(start -0.12065 0.2794)
			(end -0.12065 0.3048)
			(stroke
				(width 0.1)
				(type default)
			)
			(layer "F.Fab")
		)
		(fp_line
			(start 0.67945 0.3048)
			(end 0.120396 0.3048)
			(stroke
				(width 0.1)
				(type default)
			)
			(layer "F.Fab")
		)
		(fp_line
			(start 0.120396 0.3048)
			(end 0.120396 0.2794)
			(stroke
				(width 0.1)
				(type default)
			)
			(layer "F.Fab")
		)
		(fp_line
			(start -0.12065 0.3048)
			(end -0.67945 0.3048)
			(stroke
				(width 0.1)
				(type default)
			)
			(layer "F.Fab")
		)
		(fp_line
			(start -0.67945 0.3048)
			(end -0.67945 -0.305054)
			(stroke
				(width 0.1)
				(type default)
			)
			(layer "F.Fab")
		)
		(pad "1" smd circle
			(at -0.40005 0 90)
			(size 0 0)
			(layers "F.Cu" "F.Mask" "F.Paste")
			(net "PEX1_SPARE3")
		)
		(pad "2" smd circle
			(at 0.40005 0 90)
			(size 0 0)
			(layers "F.Cu" "F.Mask" "F.Paste")
			(net "P1V8_PEX")
		)
	)
	(footprint ""
		(layer "F.Cu")
		(at 127.185166 -115.549426 -90)
		(property "Reference" "Q214"
			(at 0.182626 1.860296 90)
			(unlocked yes)
			(layer "F.SilkS")
			(effects
				(font
					(size 0.7874 0.5842)
					(thickness 0.1524)
				)
			)
		)
		(property "Value" ""
			(at 0 0 270)
			(layer "F.Fab")
			(effects
				(font
					(size 1.27 1.27)
				)
			)
		)
		(duplicate_pad_numbers_are_jumpers no)
		(fp_line
			(start -1.376172 1.199896)
			(end -1.376172 -1.199896)
			(stroke
				(width 0.1524)
				(type default)
			)
			(layer "F.SilkS")
		)
		(fp_line
			(start 1.376172 1.199896)
			(end -1.376172 1.199896)
			(stroke
				(width 0.1524)
				(type default)
			)
			(layer "F.SilkS")
		)
		(fp_line
			(start 0 -0.762)
			(end 0.508 -1.199896)
			(stroke
				(width 0.1524)
				(type default)
			)
			(layer "F.SilkS")
		)
		(fp_line
			(start -1.376172 -1.199896)
			(end -0.508 -1.199896)
			(stroke
				(width 0.1524)
				(type default)
			)
			(layer "F.SilkS")
		)
		(fp_line
			(start -0.508 -1.199896)
			(end 0 -0.762)
			(stroke
				(width 0.1524)
				(type default)
			)
			(layer "F.SilkS")
		)
		(fp_line
			(start 0.508 -1.199896)
			(end 1.376172 -1.199896)
			(stroke
				(width 0.1524)
				(type default)
			)
			(layer "F.SilkS")
		)
		(fp_line
			(start 1.376172 -1.199896)
			(end 1.376172 1.199896)
			(stroke
				(width 0.1524)
				(type default)
			)
			(layer "F.SilkS")
		)
		(fp_poly
			(pts
				(xy -1.221486 -1.29286) (xy -1.49098 -2.101088) (xy -2.029714 -1.562354)
			)
			(stroke
				(width 0)
				(type default)
			)
			(fill yes)
			(layer "F.SilkS")
		)
		(fp_line
			(start -0.674878 1.100074)
			(end -0.674878 -1.100074)
			(stroke
				(width 0.1)
				(type default)
			)
			(layer "F.Fab")
		)
		(fp_line
			(start 0.674878 1.100074)
			(end -0.674878 1.100074)
			(stroke
				(width 0.1)
				(type default)
			)
			(layer "F.Fab")
		)
		(fp_line
			(start -0.674878 -1.100074)
			(end 0.674878 -1.100074)
			(stroke
				(width 0.1)
				(type default)
			)
			(layer "F.Fab")
		)
		(fp_line
			(start 0.674878 -1.100074)
			(end 0.674878 1.100074)
			(stroke
				(width 0.1)
				(type default)
			)
			(layer "F.Fab")
		)
		(fp_poly
			(pts
				(xy -1.4605 -0.7493) (xy -2.2225 -1.1303) (xy -2.2225 -0.3683)
			)
			(stroke
				(width 0)
				(type default)
			)
			(fill yes)
			(layer "F.Fab")
		)
		(pad "1" smd rect
			(at -0.899922 -0.750062 180)
			(size 0.6096 0.6096)
			(layers "F.Cu" "F.Mask" "F.Paste")
			(net "GND")
		)
		(pad "2" smd rect
			(at -0.899922 0 180)
			(size 0.4064 0.6096)
			(layers "F.Cu" "F.Mask" "F.Paste")
			(net "P3V3_NIC2_PG_G1")
		)
		(pad "3" smd rect
			(at -0.899922 0.750062 180)
			(size 0.6096 0.6096)
			(layers "F.Cu" "F.Mask" "F.Paste")
			(net "PWRGD_P3V3_NIC2_D")
		)
		(pad "4" smd rect
			(at 0.899922 0.750062 180)
			(size 0.6096 0.6096)
			(layers "F.Cu" "F.Mask" "F.Paste")
			(net "GND")
		)
		(pad "5" smd rect
			(at 0.899922 0 180)
			(size 0.4064 0.6096)
			(layers "F.Cu" "F.Mask" "F.Paste")
			(net "P3V3_NIC2_PG_G2")
		)
		(pad "6" smd rect
			(at 0.899922 -0.750062 180)
			(size 0.6096 0.6096)
			(layers "F.Cu" "F.Mask" "F.Paste")
			(net "P3V3_NIC2_PG_G2")
		)
	)
	(footprint ""
		(layer "F.Cu")
		(at 278.775414 -69.47916 180)
		(property "Reference" "PU112"
			(at -1.845056 4.13004 90)
			(unlocked yes)
			(layer "F.SilkS")
			(effects
				(font
					(size 0.7874 0.5842)
					(thickness 0.1524)
				)
			)
		)
		(property "Value" ""
			(at 0 0 180)
			(layer "F.Fab")
			(effects
				(font
					(size 1.27 1.27)
				)
			)
		)
		(duplicate_pad_numbers_are_jumpers no)
		(fp_line
			(start 1.239774 1.495298)
			(end -1.239774 1.495298)
			(stroke
				(width 0.1524)
				(type default)
			)
			(layer "F.SilkS")
		)
		(fp_line
			(start 1.239774 -1.495298)
			(end 1.239774 1.495298)
			(stroke
				(width 0.1524)
				(type default)
			)
			(layer "F.SilkS")
		)
		(fp_line
			(start -1.239774 1.495298)
			(end -1.239774 -1.495298)
			(stroke
				(width 0.1524)
				(type default)
			)
			(layer "F.SilkS")
		)
		(fp_line
			(start -1.239774 -1.495298)
			(end 1.239774 -1.495298)
			(stroke
				(width 0.1524)
				(type default)
			)
			(layer "F.SilkS")
		)
		(fp_poly
			(pts
				(xy -1.640586 -0.884428) (xy -2.358898 -0.166116) (xy -1.28143 0.193294)
			)
			(stroke
				(width 0)
				(type default)
			)
			(fill yes)
			(layer "F.SilkS")
		)
		(fp_line
			(start 0.8001 1.050036)
			(end -0.8001 1.050036)
			(stroke
				(width 0.1)
				(type default)
			)
			(layer "F.Fab")
		)
		(fp_line
			(start 0.8001 -1.050036)
			(end 0.8001 1.050036)
			(stroke
				(width 0.1)
				(type default)
			)
			(layer "F.Fab")
		)
		(fp_line
			(start -0.8001 1.050036)
			(end -0.8001 -1.050036)
			(stroke
				(width 0.1)
				(type default)
			)
			(layer "F.Fab")
		)
		(fp_line
			(start -0.8001 -1.050036)
			(end 0.8001 -1.050036)
			(stroke
				(width 0.1)
				(type default)
			)
			(layer "F.Fab")
		)
		(fp_poly
			(pts
				(xy -2.458974 -0.508) (xy -2.458974 0.508) (xy -1.442974 0)
			)
			(stroke
				(width 0)
				(type default)
			)
			(fill yes)
			(layer "F.Fab")
		)
		(pad "1_2" smd circle
			(at -0.374904 0 270)
			(size 0 0)
			(layers "F.Cu" "F.Mask" "F.Paste")
			(net "P12V_AUX")
		)
		(pad "3" smd rect
			(at -0.499872 0.999998 180)
			(size 0.254 0.7112)
			(layers "F.Cu" "F.Mask" "F.Paste")
			(net "GND")
		)
		(pad "4" smd rect
			(at 0 0.999998 180)
			(size 0.254 0.7112)
			(layers "F.Cu" "F.Mask" "F.Paste")
			(net "P12V_SSD9_CO_ILIMIT")
		)
		(pad "5" smd rect
			(at 0.499872 0.999998 180)
			(size 0.254 0.7112)
			(layers "F.Cu" "F.Mask" "F.Paste")
			(net "P12V_SSD9_CO_MODE")
		)
		(pad "6_7" smd circle
			(at 0.374904 0 90)
			(size 0 0)
			(layers "F.Cu" "F.Mask" "F.Paste")
			(net "P12V_SSD9_R")
		)
		(pad "8" smd rect
			(at 0.499872 -0.999998 180)
			(size 0.254 0.7112)
			(layers "F.Cu" "F.Mask" "F.Paste")
			(net "P12V_SSD9_CO_GATE")
		)
		(pad "9" smd rect
			(at 0 -0.999998 180)
			(size 0.254 0.7112)
			(layers "F.Cu" "F.Mask" "F.Paste")
			(net "P12V_SSD9_CO_EN")
		)
		(pad "10" smd rect
			(at -0.499872 -0.999998 180)
			(size 0.254 0.7112)
			(layers "F.Cu" "F.Mask" "F.Paste")
			(net "P12V_SSD9_CO_DV_DT")
		)
	)
	(footprint ""
		(layer "F.Cu")
		(at 419.557962 -72.766682 90)
		(property "Reference" "PC890"
			(at 0 0 90)
			(layer "F.SilkS")
			(hide yes)
			(effects
				(font
					(size 1.27 1.27)
				)
			)
		)
		(property "Value" ""
			(at 0 0 90)
			(layer "F.Fab")
			(effects
				(font
					(size 1.27 1.27)
				)
			)
		)
		(duplicate_pad_numbers_are_jumpers no)
		(fp_line
			(start 0.7874 -0.4064)
			(end 0.7874 0.4064)
			(stroke
				(width 0.1524)
				(type default)
			)
			(layer "F.SilkS")
		)
		(fp_line
			(start -0.7874 -0.4064)
			(end 0.7874 -0.4064)
			(stroke
				(width 0.1524)
				(type default)
			)
			(layer "F.SilkS")
		)
		(fp_line
			(start 0.7874 0.4064)
			(end -0.7874 0.4064)
			(stroke
				(width 0.1524)
				(type default)
			)
			(layer "F.SilkS")
		)
		(fp_line
			(start -0.7874 0.4064)
			(end -0.7874 -0.4064)
			(stroke
				(width 0.1524)
				(type default)
			)
			(layer "F.SilkS")
		)
		(fp_line
			(start -0.12065 -0.305054)
			(end -0.12065 -0.2794)
			(stroke
				(width 0.1)
				(type default)
			)
			(layer "F.Fab")
		)
		(fp_line
			(start -0.67945 -0.305054)
			(end -0.12065 -0.305054)
			(stroke
				(width 0.1)
				(type default)
			)
			(layer "F.Fab")
		)
		(fp_line
			(start 0.67945 -0.3048)
			(end 0.67945 0.3048)
			(stroke
				(width 0.1)
				(type default)
			)
			(layer "F.Fab")
		)
		(fp_line
			(start 0.12065 -0.3048)
			(end 0.67945 -0.3048)
			(stroke
				(width 0.1)
				(type default)
			)
			(layer "F.Fab")
		)
		(fp_line
			(start 0.12065 -0.2794)
			(end 0.12065 -0.3048)
			(stroke
				(width 0.1)
				(type default)
			)
			(layer "F.Fab")
		)
		(fp_line
			(start -0.12065 -0.2794)
			(end 0.12065 -0.2794)
			(stroke
				(width 0.1)
				(type default)
			)
			(layer "F.Fab")
		)
		(fp_line
			(start 0.120396 0.2794)
			(end -0.12065 0.2794)
			(stroke
				(width 0.1)
				(type default)
			)
			(layer "F.Fab")
		)
		(fp_line
			(start -0.12065 0.2794)
			(end -0.12065 0.3048)
			(stroke
				(width 0.1)
				(type default)
			)
			(layer "F.Fab")
		)
		(fp_line
			(start 0.67945 0.3048)
			(end 0.120396 0.3048)
			(stroke
				(width 0.1)
				(type default)
			)
			(layer "F.Fab")
		)
		(fp_line
			(start 0.120396 0.3048)
			(end 0.120396 0.2794)
			(stroke
				(width 0.1)
				(type default)
			)
			(layer "F.Fab")
		)
		(fp_line
			(start -0.12065 0.3048)
			(end -0.67945 0.3048)
			(stroke
				(width 0.1)
				(type default)
			)
			(layer "F.Fab")
		)
		(fp_line
			(start -0.67945 0.3048)
			(end -0.67945 -0.305054)
			(stroke
				(width 0.1)
				(type default)
			)
			(layer "F.Fab")
		)
		(pad "1" smd circle
			(at -0.40005 0 90)
			(size 0 0)
			(layers "F.Cu" "F.Mask" "F.Paste")
			(net "P12V_SSD14_CO_MODE")
		)
		(pad "2" smd circle
			(at 0.40005 0 90)
			(size 0 0)
			(layers "F.Cu" "F.Mask" "F.Paste")
			(net "GND")
		)
	)
	(footprint ""
		(layer "F.Cu")
		(at 361.335066 -279.101804)
		(property "Reference" "PC188"
			(at 0 0 0)
			(layer "F.SilkS")
			(hide yes)
			(effects
				(font
					(size 1.27 1.27)
				)
			)
		)
		(property "Value" ""
			(at 0 0 0)
			(layer "F.Fab")
			(effects
				(font
					(size 1.27 1.27)
				)
			)
		)
		(duplicate_pad_numbers_are_jumpers no)
		(fp_line
			(start -0.7874 -0.4064)
			(end 0.7874 -0.4064)
			(stroke
				(width 0.1524)
				(type default)
			)
			(layer "F.SilkS")
		)
		(fp_line
			(start -0.7874 0.4064)
			(end -0.7874 -0.4064)
			(stroke
				(width 0.1524)
				(type default)
			)
			(layer "F.SilkS")
		)
		(fp_line
			(start 0.7874 -0.4064)
			(end 0.7874 0.4064)
			(stroke
				(width 0.1524)
				(type default)
			)
			(layer "F.SilkS")
		)
		(fp_line
			(start 0.7874 0.4064)
			(end -0.7874 0.4064)
			(stroke
				(width 0.1524)
				(type default)
			)
			(layer "F.SilkS")
		)
		(fp_line
			(start -0.67945 -0.305054)
			(end -0.12065 -0.305054)
			(stroke
				(width 0.1)
				(type default)
			)
			(layer "F.Fab")
		)
		(fp_line
			(start -0.67945 0.3048)
			(end -0.67945 -0.305054)
			(stroke
				(width 0.1)
				(type default)
			)
			(layer "F.Fab")
		)
		(fp_line
			(start -0.12065 -0.305054)
			(end -0.12065 -0.2794)
			(stroke
				(width 0.1)
				(type default)
			)
			(layer "F.Fab")
		)
		(fp_line
			(start -0.12065 -0.2794)
			(end 0.12065 -0.2794)
			(stroke
				(width 0.1)
				(type default)
			)
			(layer "F.Fab")
		)
		(fp_line
			(start -0.12065 0.2794)
			(end -0.12065 0.3048)
			(stroke
				(width 0.1)
				(type default)
			)
			(layer "F.Fab")
		)
		(fp_line
			(start -0.12065 0.3048)
			(end -0.67945 0.3048)
			(stroke
				(width 0.1)
				(type default)
			)
			(layer "F.Fab")
		)
		(fp_line
			(start 0.120396 0.2794)
			(end -0.12065 0.2794)
			(stroke
				(width 0.1)
				(type default)
			)
			(layer "F.Fab")
		)
		(fp_line
			(start 0.120396 0.3048)
			(end 0.120396 0.2794)
			(stroke
				(width 0.1)
				(type default)
			)
			(layer "F.Fab")
		)
		(fp_line
			(start 0.12065 -0.3048)
			(end 0.67945 -0.3048)
			(stroke
				(width 0.1)
				(type default)
			)
			(layer "F.Fab")
		)
		(fp_line
			(start 0.12065 -0.2794)
			(end 0.12065 -0.3048)
			(stroke
				(width 0.1)
				(type default)
			)
			(layer "F.Fab")
		)
		(fp_line
			(start 0.67945 -0.3048)
			(end 0.67945 0.3048)
			(stroke
				(width 0.1)
				(type default)
			)
			(layer "F.Fab")
		)
		(fp_line
			(start 0.67945 0.3048)
			(end 0.120396 0.3048)
			(stroke
				(width 0.1)
				(type default)
			)
			(layer "F.Fab")
		)
		(pad "1" smd circle
			(at -0.40005 0)
			(size 0 0)
			(layers "F.Cu" "F.Mask" "F.Paste")
			(net "SW_P12V_P0V8_PEX3_FLT")
		)
		(pad "2" smd circle
			(at 0.40005 0)
			(size 0 0)
			(layers "F.Cu" "F.Mask" "F.Paste")
			(net "GND")
		)
	)
	(footprint ""
		(layer "F.Cu")
		(at 87.918544 -302.907954 -90)
		(property "Reference" "R6805"
			(at 0 0 270)
			(layer "F.SilkS")
			(hide yes)
			(effects
				(font
					(size 1.27 1.27)
				)
			)
		)
		(property "Value" ""
			(at 0 0 270)
			(layer "F.Fab")
			(effects
				(font
					(size 1.27 1.27)
				)
			)
		)
		(duplicate_pad_numbers_are_jumpers no)
		(fp_line
			(start -0.7874 0.4064)
			(end -0.7874 -0.4064)
			(stroke
				(width 0.1524)
				(type default)
			)
			(layer "F.SilkS")
		)
		(fp_line
			(start 0.7874 0.4064)
			(end -0.7874 0.4064)
			(stroke
				(width 0.1524)
				(type default)
			)
			(layer "F.SilkS")
		)
		(fp_line
			(start -0.7874 -0.4064)
			(end 0.7874 -0.4064)
			(stroke
				(width 0.1524)
				(type default)
			)
			(layer "F.SilkS")
		)
		(fp_line
			(start 0.7874 -0.4064)
			(end 0.7874 0.4064)
			(stroke
				(width 0.1524)
				(type default)
			)
			(layer "F.SilkS")
		)
		(fp_line
			(start -0.67945 0.3048)
			(end -0.67945 -0.305054)
			(stroke
				(width 0.1)
				(type default)
			)
			(layer "F.Fab")
		)
		(fp_line
			(start -0.12065 0.3048)
			(end -0.67945 0.3048)
			(stroke
				(width 0.1)
				(type default)
			)
			(layer "F.Fab")
		)
		(fp_line
			(start 0.120396 0.3048)
			(end 0.120396 0.2794)
			(stroke
				(width 0.1)
				(type default)
			)
			(layer "F.Fab")
		)
		(fp_line
			(start 0.67945 0.3048)
			(end 0.120396 0.3048)
			(stroke
				(width 0.1)
				(type default)
			)
			(layer "F.Fab")
		)
		(fp_line
			(start -0.12065 0.2794)
			(end -0.12065 0.3048)
			(stroke
				(width 0.1)
				(type default)
			)
			(layer "F.Fab")
		)
		(fp_line
			(start 0.120396 0.2794)
			(end -0.12065 0.2794)
			(stroke
				(width 0.1)
				(type default)
			)
			(layer "F.Fab")
		)
		(fp_line
			(start -0.12065 -0.2794)
			(end 0.12065 -0.2794)
			(stroke
				(width 0.1)
				(type default)
			)
			(layer "F.Fab")
		)
		(fp_line
			(start 0.12065 -0.2794)
			(end 0.12065 -0.3048)
			(stroke
				(width 0.1)
				(type default)
			)
			(layer "F.Fab")
		)
		(fp_line
			(start 0.12065 -0.3048)
			(end 0.67945 -0.3048)
			(stroke
				(width 0.1)
				(type default)
			)
			(layer "F.Fab")
		)
		(fp_line
			(start 0.67945 -0.3048)
			(end 0.67945 0.3048)
			(stroke
				(width 0.1)
				(type default)
			)
			(layer "F.Fab")
		)
		(fp_line
			(start -0.67945 -0.305054)
			(end -0.12065 -0.305054)
			(stroke
				(width 0.1)
				(type default)
			)
			(layer "F.Fab")
		)
		(fp_line
			(start -0.12065 -0.305054)
			(end -0.12065 -0.2794)
			(stroke
				(width 0.1)
				(type default)
			)
			(layer "F.Fab")
		)
		(pad "1" smd circle
			(at -0.40005 0 270)
			(size 0 0)
			(layers "F.Cu" "F.Mask" "F.Paste")
			(net "SMB_PEX0_R_SDA")
		)
		(pad "2" smd circle
			(at 0.40005 0 270)
			(size 0 0)
			(layers "F.Cu" "F.Mask" "F.Paste")
			(net "SMB_PEX0_SDA")
		)
	)
)
